(kicad_pcb
	(version 20260206)
	(generator "pcbnew")
	(generator_version "10.0")
	(general
		(thickness 1.6)
		(legacy_teardrops no)
	)
	(paper "A4")
	(title_block
		(title "15969-1a.1015WZS0858.brd")
		(comment 1 "Tioga Pass / footprints 218-225 of 295")
	)
	(layers
		(0 "F.Cu" signal "TOP")
		(4 "In1.Cu" signal "L2GND")
		(6 "In2.Cu" signal "L3")
		(8 "In3.Cu" signal "L4")
		(10 "In4.Cu" signal "L5GND")
		(2 "B.Cu" signal "BOTTOM")
		(9 "F.Adhes" user "F.Adhesive")
		(11 "B.Adhes" user "B.Adhesive")
		(13 "F.Paste" user "Package Geometry/Pastemask Top")
		(15 "B.Paste" user "Package Geometry/Pastemask Bottom")
		(5 "F.SilkS" user "Ref Des/Silkscreen Top")
		(7 "B.SilkS" user "Ref Des/Silkscreen Bottom")
		(1 "F.Mask" user "Board Geometry/Soldermask Top")
		(3 "B.Mask" user "Board Geometry/Soldermask Bottom")
		(17 "Dwgs.User" user "User.Drawings")
		(19 "Cmts.User" user "User.Comments")
		(21 "Eco1.User" user "User.Eco1")
		(23 "Eco2.User" user "User.Eco2")
		(25 "Edge.Cuts" user "Board Geometry/Outline")
		(27 "Margin" user)
		(31 "F.CrtYd" user "Package Geometry/Place Bound Top")
		(29 "B.CrtYd" user "Package Geometry/Place Bound Bottom")
		(35 "F.Fab" user "Ref Des/Assembly Top")
		(33 "B.Fab" user "Ref Des/Assembly Bottom")
	)
	(footprint ""
		(layer "B.Cu")
		(at 20.768818 -6.320028 -90)
		(property "Reference" "PC3"
			(at 0 0 90)
			(layer "B.SilkS")
			(hide yes)
			(effects
				(font
					(size 1.27 1.27)
				)
				(justify mirror)
			)
		)
		(property "Value" "SCD1U16V2KX-3GP"
			(at -1.1811 -2.7051 270)
			(unlocked yes)
			(layer "B.Fab")
			(hide yes)
			(effects
				(font
					(size 1.016 1.016)
					(thickness 0.1524)
				)
				(justify mirror)
			)
		)
		(property "Device Type" "C402H22"
			(at -1.1811 -4.2291 270)
			(unlocked yes)
			(layer "B.Fab")
			(hide yes)
			(effects
				(font
					(size 1.016 1.016)
					(thickness 0.1524)
				)
				(justify mirror)
			)
		)
		(duplicate_pad_numbers_are_jumpers no)
		(fp_rect
			(start 0.4318 0.9525)
			(end -0.4318 -0.9525)
			(stroke
				(width 0)
				(type default)
			)
			(fill no)
			(layer "B.CrtYd")
		)
		(fp_rect
			(start 0.4318 0.9525)
			(end -0.4318 -0.9525)
			(stroke
				(width 0)
				(type default)
			)
			(fill no)
			(layer "B.Fab")
		)
		(pad "1" smd custom
			(at 0 -0.4445 90)
			(size 0.1524 0.1524)
			(layers "B.Cu" "B.Mask" "B.Paste")
			(net "P3V3_VIN")
			(options
				(clearance outline)
				(anchor circle)
			)
			(primitives
				(gr_poly
					(pts
						(arc
							(start 0.3048 0.2032)
							(mid 0.275042 0.275042)
							(end 0.2032 0.3048)
						)
						(arc
							(start -0.2032 0.3048)
							(mid -0.275042 0.275042)
							(end -0.3048 0.2032)
						)
						(arc
							(start -0.3048 -0.2032)
							(mid -0.275042 -0.275042)
							(end -0.2032 -0.3048)
						)
						(arc
							(start 0.2032 -0.3048)
							(mid 0.275042 -0.275042)
							(end 0.3048 -0.2032)
						)
					)
					(width 0)
					(fill yes)
				)
			)
		)
		(pad "2" smd custom
			(at 0 0.4445 90)
			(size 0.1524 0.1524)
			(layers "B.Cu" "B.Mask" "B.Paste")
			(net "GND")
			(options
				(clearance outline)
				(anchor circle)
			)
			(primitives
				(gr_poly
					(pts
						(arc
							(start 0.3048 0.2032)
							(mid 0.275042 0.275042)
							(end 0.2032 0.3048)
						)
						(arc
							(start -0.2032 0.3048)
							(mid -0.275042 0.275042)
							(end -0.3048 0.2032)
						)
						(arc
							(start -0.3048 -0.2032)
							(mid -0.275042 -0.275042)
							(end -0.2032 -0.3048)
						)
						(arc
							(start 0.2032 -0.3048)
							(mid 0.275042 -0.275042)
							(end 0.3048 -0.2032)
						)
					)
					(width 0)
					(fill yes)
				)
			)
		)
	)
	(footprint ""
		(layer "B.Cu")
		(at 121.5644 -27.6098 90)
		(property "Reference" "CU4"
			(at 0 0 90)
			(layer "B.SilkS")
			(hide yes)
			(effects
				(font
					(size 1.27 1.27)
				)
				(justify mirror)
			)
		)
		(property "Value" "SC1U10V2KX-4-GP"
			(at -1.1811 -2.7051 90)
			(unlocked yes)
			(layer "B.Fab")
			(hide yes)
			(effects
				(font
					(size 1.016 1.016)
					(thickness 0.1524)
				)
				(justify mirror)
			)
		)
		(property "Device Type" "C402H22"
			(at -1.1811 -4.2291 90)
			(unlocked yes)
			(layer "B.Fab")
			(hide yes)
			(effects
				(font
					(size 1.016 1.016)
					(thickness 0.1524)
				)
				(justify mirror)
			)
		)
		(duplicate_pad_numbers_are_jumpers no)
		(fp_rect
			(start 0.4318 0.9525)
			(end -0.4318 -0.9525)
			(stroke
				(width 0)
				(type default)
			)
			(fill no)
			(layer "B.CrtYd")
		)
		(fp_rect
			(start 0.4318 0.9525)
			(end -0.4318 -0.9525)
			(stroke
				(width 0)
				(type default)
			)
			(fill no)
			(layer "B.Fab")
		)
		(pad "1" smd custom
			(at 0 -0.4445 270)
			(size 0.1524 0.1524)
			(layers "B.Cu" "B.Mask" "B.Paste")
			(net "P3V3_USB_HUB")
			(options
				(clearance outline)
				(anchor circle)
			)
			(primitives
				(gr_poly
					(pts
						(arc
							(start 0.3048 0.2032)
							(mid 0.275042 0.275042)
							(end 0.2032 0.3048)
						)
						(arc
							(start -0.2032 0.3048)
							(mid -0.275042 0.275042)
							(end -0.3048 0.2032)
						)
						(arc
							(start -0.3048 -0.2032)
							(mid -0.275042 -0.275042)
							(end -0.2032 -0.3048)
						)
						(arc
							(start 0.2032 -0.3048)
							(mid 0.275042 -0.275042)
							(end 0.3048 -0.2032)
						)
					)
					(width 0)
					(fill yes)
				)
			)
		)
		(pad "2" smd custom
			(at 0 0.4445 270)
			(size 0.1524 0.1524)
			(layers "B.Cu" "B.Mask" "B.Paste")
			(net "GND")
			(options
				(clearance outline)
				(anchor circle)
			)
			(primitives
				(gr_poly
					(pts
						(arc
							(start 0.3048 0.2032)
							(mid 0.275042 0.275042)
							(end 0.2032 0.3048)
						)
						(arc
							(start -0.2032 0.3048)
							(mid -0.275042 0.275042)
							(end -0.3048 0.2032)
						)
						(arc
							(start -0.3048 -0.2032)
							(mid -0.275042 -0.275042)
							(end -0.2032 -0.3048)
						)
						(arc
							(start 0.2032 -0.3048)
							(mid 0.275042 -0.275042)
							(end 0.3048 -0.2032)
						)
					)
					(width 0)
					(fill yes)
				)
			)
		)
	)
	(footprint ""
		(layer "B.Cu")
		(at 26.6446 -19.4056 180)
		(property "Reference" "R88"
			(at 0 0 0)
			(layer "B.SilkS")
			(hide yes)
			(effects
				(font
					(size 1.27 1.27)
				)
				(justify mirror)
			)
		)
		(property "Value" "0R2F-1-GP"
			(at -0.064008 -3.993896 180)
			(unlocked yes)
			(layer "B.Fab")
			(hide yes)
			(effects
				(font
					(size 1.016 1.016)
					(thickness 0.1524)
				)
				(justify mirror)
			)
		)
		(property "Device Type" "R402H16"
			(at -0.064008 -5.517896 180)
			(unlocked yes)
			(layer "B.Fab")
			(hide yes)
			(effects
				(font
					(size 1.016 1.016)
					(thickness 0.1524)
				)
				(justify mirror)
			)
		)
		(duplicate_pad_numbers_are_jumpers no)
		(fp_line
			(start 0.508 -0.9398)
			(end 0.508 0.9398)
			(stroke
				(width 0.1524)
				(type default)
			)
			(layer "B.SilkS")
		)
		(fp_line
			(start -0.508 -0.9398)
			(end 0.508 -0.9398)
			(stroke
				(width 0.1524)
				(type default)
			)
			(layer "B.SilkS")
		)
		(fp_rect
			(start 0.508 0.9398)
			(end -0.508 -0.9398)
			(stroke
				(width 0)
				(type default)
			)
			(fill no)
			(layer "B.CrtYd")
		)
		(fp_rect
			(start 0.508 0.9398)
			(end -0.508 -0.9398)
			(stroke
				(width 0)
				(type default)
			)
			(fill no)
			(layer "B.Fab")
		)
		(pad "1" smd custom
			(at 0 -0.4445)
			(size 0.1397 0.1397)
			(layers "B.Cu" "B.Mask" "B.Paste")
			(net "SMB_VMONITOR_SLOT3_MUX_SDA")
			(options
				(clearance outline)
				(anchor circle)
			)
			(primitives
				(gr_poly
					(pts
						(arc
							(start -0.1778 0.2794)
							(mid -0.249642 0.249642)
							(end -0.2794 0.1778)
						)
						(arc
							(start -0.2794 -0.1778)
							(mid -0.249642 -0.249642)
							(end -0.1778 -0.2794)
						)
						(arc
							(start 0.1778 -0.2794)
							(mid 0.249642 -0.249642)
							(end 0.2794 -0.1778)
						)
						(arc
							(start 0.2794 0.1778)
							(mid 0.249642 0.249642)
							(end 0.1778 0.2794)
						)
					)
					(width 0)
					(fill yes)
				)
			)
		)
		(pad "2" smd custom
			(at 0 0.4445)
			(size 0.1397 0.1397)
			(layers "B.Cu" "B.Mask" "B.Paste")
			(net "SMDAT_BMC_DEVICE")
			(options
				(clearance outline)
				(anchor circle)
			)
			(primitives
				(gr_poly
					(pts
						(arc
							(start -0.1778 0.2794)
							(mid -0.249642 0.249642)
							(end -0.2794 0.1778)
						)
						(arc
							(start -0.2794 -0.1778)
							(mid -0.249642 -0.249642)
							(end -0.1778 -0.2794)
						)
						(arc
							(start 0.1778 -0.2794)
							(mid 0.249642 -0.249642)
							(end 0.2794 -0.1778)
						)
						(arc
							(start 0.2794 0.1778)
							(mid 0.249642 0.249642)
							(end 0.1778 0.2794)
						)
					)
					(width 0)
					(fill yes)
				)
			)
		)
	)
	(footprint ""
		(layer "B.Cu")
		(at 33.9852 5.461 -90)
		(property "Reference" "R106"
			(at 0 0 90)
			(layer "B.SilkS")
			(hide yes)
			(effects
				(font
					(size 1.27 1.27)
				)
				(justify mirror)
			)
		)
		(property "Value" "10KR2F-2-GP"
			(at -0.064008 -3.993896 270)
			(unlocked yes)
			(layer "B.Fab")
			(hide yes)
			(effects
				(font
					(size 1.016 1.016)
					(thickness 0.1524)
				)
				(justify mirror)
			)
		)
		(property "Device Type" "R402H16"
			(at -0.064008 -5.517896 270)
			(unlocked yes)
			(layer "B.Fab")
			(hide yes)
			(effects
				(font
					(size 1.016 1.016)
					(thickness 0.1524)
				)
				(justify mirror)
			)
		)
		(duplicate_pad_numbers_are_jumpers no)
		(fp_line
			(start -0.508 -0.9398)
			(end 0.508 -0.9398)
			(stroke
				(width 0.1524)
				(type default)
			)
			(layer "B.SilkS")
		)
		(fp_line
			(start 0.508 -0.9398)
			(end 0.508 0.9398)
			(stroke
				(width 0.1524)
				(type default)
			)
			(layer "B.SilkS")
		)
		(fp_rect
			(start 0.508 0.9398)
			(end -0.508 -0.9398)
			(stroke
				(width 0)
				(type default)
			)
			(fill no)
			(layer "B.CrtYd")
		)
		(fp_rect
			(start 0.508 0.9398)
			(end -0.508 -0.9398)
			(stroke
				(width 0)
				(type default)
			)
			(fill no)
			(layer "B.Fab")
		)
		(pad "1" smd custom
			(at 0 -0.4445 90)
			(size 0.1397 0.1397)
			(layers "B.Cu" "B.Mask" "B.Paste")
			(net "SMB_P_REPEATER_EN")
			(options
				(clearance outline)
				(anchor circle)
			)
			(primitives
				(gr_poly
					(pts
						(arc
							(start -0.1778 0.2794)
							(mid -0.249642 0.249642)
							(end -0.2794 0.1778)
						)
						(arc
							(start -0.2794 -0.1778)
							(mid -0.249642 -0.249642)
							(end -0.1778 -0.2794)
						)
						(arc
							(start 0.1778 -0.2794)
							(mid 0.249642 -0.249642)
							(end 0.2794 -0.1778)
						)
						(arc
							(start 0.2794 0.1778)
							(mid 0.249642 0.249642)
							(end 0.1778 0.2794)
						)
					)
					(width 0)
					(fill yes)
				)
			)
		)
		(pad "2" smd custom
			(at 0 0.4445 90)
			(size 0.1397 0.1397)
			(layers "B.Cu" "B.Mask" "B.Paste")
			(net "P3V3_STBY")
			(options
				(clearance outline)
				(anchor circle)
			)
			(primitives
				(gr_poly
					(pts
						(arc
							(start -0.1778 0.2794)
							(mid -0.249642 0.249642)
							(end -0.2794 0.1778)
						)
						(arc
							(start -0.2794 -0.1778)
							(mid -0.249642 -0.249642)
							(end -0.1778 -0.2794)
						)
						(arc
							(start 0.1778 -0.2794)
							(mid 0.249642 -0.249642)
							(end 0.2794 -0.1778)
						)
						(arc
							(start 0.2794 0.1778)
							(mid 0.249642 0.249642)
							(end 0.1778 0.2794)
						)
					)
					(width 0)
					(fill yes)
				)
			)
		)
	)
	(footprint ""
		(layer "B.Cu")
		(at 132.2324 -4.8514 90)
		(property "Reference" "R72"
			(at 0 0 90)
			(layer "B.SilkS")
			(hide yes)
			(effects
				(font
					(size 1.27 1.27)
				)
				(justify mirror)
			)
		)
		(property "Value" "10KR2F-2-GP"
			(at -0.064008 -3.993896 90)
			(unlocked yes)
			(layer "B.Fab")
			(hide yes)
			(effects
				(font
					(size 1.016 1.016)
					(thickness 0.1524)
				)
				(justify mirror)
			)
		)
		(property "Device Type" "R402H16"
			(at -0.064008 -5.517896 90)
			(unlocked yes)
			(layer "B.Fab")
			(hide yes)
			(effects
				(font
					(size 1.016 1.016)
					(thickness 0.1524)
				)
				(justify mirror)
			)
		)
		(duplicate_pad_numbers_are_jumpers no)
		(fp_line
			(start 0.508 -0.9398)
			(end 0.508 0.9398)
			(stroke
				(width 0.1524)
				(type default)
			)
			(layer "B.SilkS")
		)
		(fp_line
			(start -0.508 -0.9398)
			(end 0.508 -0.9398)
			(stroke
				(width 0.1524)
				(type default)
			)
			(layer "B.SilkS")
		)
		(fp_rect
			(start 0.508 0.9398)
			(end -0.508 -0.9398)
			(stroke
				(width 0)
				(type default)
			)
			(fill no)
			(layer "B.CrtYd")
		)
		(fp_rect
			(start 0.508 0.9398)
			(end -0.508 -0.9398)
			(stroke
				(width 0)
				(type default)
			)
			(fill no)
			(layer "B.Fab")
		)
		(pad "1" smd custom
			(at 0 -0.4445 270)
			(size 0.1397 0.1397)
			(layers "B.Cu" "B.Mask" "B.Paste")
			(net "SMB_PCH_DEVICE_ALERT_N")
			(options
				(clearance outline)
				(anchor circle)
			)
			(primitives
				(gr_poly
					(pts
						(arc
							(start -0.1778 0.2794)
							(mid -0.249642 0.249642)
							(end -0.2794 0.1778)
						)
						(arc
							(start -0.2794 -0.1778)
							(mid -0.249642 -0.249642)
							(end -0.1778 -0.2794)
						)
						(arc
							(start 0.1778 -0.2794)
							(mid 0.249642 -0.249642)
							(end 0.2794 -0.1778)
						)
						(arc
							(start 0.2794 0.1778)
							(mid 0.249642 0.249642)
							(end 0.1778 0.2794)
						)
					)
					(width 0)
					(fill yes)
				)
			)
		)
		(pad "2" smd custom
			(at 0 0.4445 270)
			(size 0.1397 0.1397)
			(layers "B.Cu" "B.Mask" "B.Paste")
			(net "P3V3_STBY")
			(options
				(clearance outline)
				(anchor circle)
			)
			(primitives
				(gr_poly
					(pts
						(arc
							(start -0.1778 0.2794)
							(mid -0.249642 0.249642)
							(end -0.2794 0.1778)
						)
						(arc
							(start -0.2794 -0.1778)
							(mid -0.249642 -0.249642)
							(end -0.1778 -0.2794)
						)
						(arc
							(start 0.1778 -0.2794)
							(mid 0.249642 -0.249642)
							(end 0.2794 -0.1778)
						)
						(arc
							(start 0.2794 0.1778)
							(mid 0.249642 0.249642)
							(end 0.1778 0.2794)
						)
					)
					(width 0)
					(fill yes)
				)
			)
		)
	)
	(footprint ""
		(layer "B.Cu")
		(at 23.1267 -19.9898)
		(property "Reference" "R105"
			(at 0 0 0)
			(layer "B.SilkS")
			(hide yes)
			(effects
				(font
					(size 1.27 1.27)
				)
				(justify mirror)
			)
		)
		(property "Value" "0R2F-1-GP"
			(at -0.064008 -3.993896 0)
			(unlocked yes)
			(layer "B.Fab")
			(hide yes)
			(effects
				(font
					(size 1.016 1.016)
					(thickness 0.1524)
				)
				(justify mirror)
			)
		)
		(property "Device Type" "R402H16"
			(at -0.064008 -5.517896 0)
			(unlocked yes)
			(layer "B.Fab")
			(hide yes)
			(effects
				(font
					(size 1.016 1.016)
					(thickness 0.1524)
				)
				(justify mirror)
			)
		)
		(duplicate_pad_numbers_are_jumpers no)
		(fp_line
			(start -0.508 -0.9398)
			(end 0.508 -0.9398)
			(stroke
				(width 0.1524)
				(type default)
			)
			(layer "B.SilkS")
		)
		(fp_line
			(start 0.508 -0.9398)
			(end 0.508 0.9398)
			(stroke
				(width 0.1524)
				(type default)
			)
			(layer "B.SilkS")
		)
		(fp_rect
			(start 0.508 0.9398)
			(end -0.508 -0.9398)
			(stroke
				(width 0)
				(type default)
			)
			(fill no)
			(layer "B.CrtYd")
		)
		(fp_rect
			(start 0.508 0.9398)
			(end -0.508 -0.9398)
			(stroke
				(width 0)
				(type default)
			)
			(fill no)
			(layer "B.Fab")
		)
		(pad "1" smd custom
			(at 0 -0.4445 180)
			(size 0.1397 0.1397)
			(layers "B.Cu" "B.Mask" "B.Paste")
			(net "SMB_VMONITOR_ATX_MUX_SCL")
			(options
				(clearance outline)
				(anchor circle)
			)
			(primitives
				(gr_poly
					(pts
						(arc
							(start -0.1778 0.2794)
							(mid -0.249642 0.249642)
							(end -0.2794 0.1778)
						)
						(arc
							(start -0.2794 -0.1778)
							(mid -0.249642 -0.249642)
							(end -0.1778 -0.2794)
						)
						(arc
							(start 0.1778 -0.2794)
							(mid 0.249642 -0.249642)
							(end 0.2794 -0.1778)
						)
						(arc
							(start 0.2794 0.1778)
							(mid 0.249642 0.249642)
							(end 0.1778 0.2794)
						)
					)
					(width 0)
					(fill yes)
				)
			)
		)
		(pad "2" smd custom
			(at 0 0.4445 180)
			(size 0.1397 0.1397)
			(layers "B.Cu" "B.Mask" "B.Paste")
			(net "SMCLK_BMC_DEVICE")
			(options
				(clearance outline)
				(anchor circle)
			)
			(primitives
				(gr_poly
					(pts
						(arc
							(start -0.1778 0.2794)
							(mid -0.249642 0.249642)
							(end -0.2794 0.1778)
						)
						(arc
							(start -0.2794 -0.1778)
							(mid -0.249642 -0.249642)
							(end -0.1778 -0.2794)
						)
						(arc
							(start 0.1778 -0.2794)
							(mid 0.249642 -0.249642)
							(end 0.2794 -0.1778)
						)
						(arc
							(start 0.2794 0.1778)
							(mid 0.249642 0.249642)
							(end 0.1778 0.2794)
						)
					)
					(width 0)
					(fill yes)
				)
			)
		)
	)
	(footprint ""
		(layer "B.Cu")
		(at 128.4478 -10.4394 90)
		(property "Reference" "R22"
			(at 0 0 90)
			(layer "B.SilkS")
			(hide yes)
			(effects
				(font
					(size 1.27 1.27)
				)
				(justify mirror)
			)
		)
		(property "Value" "4K7R2F-GP"
			(at -0.064008 -3.993896 90)
			(unlocked yes)
			(layer "B.Fab")
			(hide yes)
			(effects
				(font
					(size 1.016 1.016)
					(thickness 0.1524)
				)
				(justify mirror)
			)
		)
		(property "Device Type" "R402H16"
			(at -0.064008 -5.517896 90)
			(unlocked yes)
			(layer "B.Fab")
			(hide yes)
			(effects
				(font
					(size 1.016 1.016)
					(thickness 0.1524)
				)
				(justify mirror)
			)
		)
		(duplicate_pad_numbers_are_jumpers no)
		(fp_line
			(start 0.508 -0.9398)
			(end 0.508 0.9398)
			(stroke
				(width 0.1524)
				(type default)
			)
			(layer "B.SilkS")
		)
		(fp_line
			(start -0.508 -0.9398)
			(end 0.508 -0.9398)
			(stroke
				(width 0.1524)
				(type default)
			)
			(layer "B.SilkS")
		)
		(fp_rect
			(start 0.508 0.9398)
			(end -0.508 -0.9398)
			(stroke
				(width 0)
				(type default)
			)
			(fill no)
			(layer "B.CrtYd")
		)
		(fp_rect
			(start 0.508 0.9398)
			(end -0.508 -0.9398)
			(stroke
				(width 0)
				(type default)
			)
			(fill no)
			(layer "B.Fab")
		)
		(pad "1" smd custom
			(at 0 -0.4445 270)
			(size 0.1397 0.1397)
			(layers "B.Cu" "B.Mask" "B.Paste")
			(net "P3V3_STBY")
			(options
				(clearance outline)
				(anchor circle)
			)
			(primitives
				(gr_poly
					(pts
						(arc
							(start -0.1778 0.2794)
							(mid -0.249642 0.249642)
							(end -0.2794 0.1778)
						)
						(arc
							(start -0.2794 -0.1778)
							(mid -0.249642 -0.249642)
							(end -0.1778 -0.2794)
						)
						(arc
							(start 0.1778 -0.2794)
							(mid 0.249642 -0.249642)
							(end 0.2794 -0.1778)
						)
						(arc
							(start 0.2794 0.1778)
							(mid 0.249642 0.249642)
							(end 0.1778 0.2794)
						)
					)
					(width 0)
					(fill yes)
				)
			)
		)
		(pad "2" smd custom
			(at 0 0.4445 270)
			(size 0.1397 0.1397)
			(layers "B.Cu" "B.Mask" "B.Paste")
			(net "SMDAT_PCH_SLOT3")
			(options
				(clearance outline)
				(anchor circle)
			)
			(primitives
				(gr_poly
					(pts
						(arc
							(start -0.1778 0.2794)
							(mid -0.249642 0.249642)
							(end -0.2794 0.1778)
						)
						(arc
							(start -0.2794 -0.1778)
							(mid -0.249642 -0.249642)
							(end -0.1778 -0.2794)
						)
						(arc
							(start 0.1778 -0.2794)
							(mid 0.249642 -0.249642)
							(end 0.2794 -0.1778)
						)
						(arc
							(start 0.2794 0.1778)
							(mid 0.249642 0.249642)
							(end 0.1778 0.2794)
						)
					)
					(width 0)
					(fill yes)
				)
			)
		)
	)
	(footprint ""
		(layer "B.Cu")
		(at 120.3579 -26.4795)
		(property "Reference" "TP81"
			(at 0 0 0)
			(layer "B.SilkS")
			(hide yes)
			(effects
				(font
					(size 1.27 1.27)
				)
				(justify mirror)
			)
		)
		(property "Value" "TPAD24"
			(at 0 -1.6129 0)
			(unlocked yes)
			(layer "B.Fab")
			(hide yes)
			(effects
				(font
					(size 1.016 1.016)
					(thickness 0.1524)
				)
				(justify mirror)
			)
		)
		(property "Device Type" "TPAD24"
			(at 0 -3.1369 0)
			(unlocked yes)
			(layer "B.Fab")
			(hide yes)
			(effects
				(font
					(size 1.016 1.016)
					(thickness 0.1524)
				)
				(justify mirror)
			)
		)
		(duplicate_pad_numbers_are_jumpers no)
		(fp_poly
			(pts
				(arc
					(start 0.3048 0)
					(mid -0.3048 0)
					(end 0.3048 0)
				)
			)
			(stroke
				(width 0)
				(type default)
			)
			(fill no)
			(layer "B.CrtYd")
		)
		(fp_poly
			(pts
				(arc
					(start 0.6096 0)
					(mid -0.6096 0)
					(end 0.6096 0)
				)
			)
			(stroke
				(width 0)
				(type default)
			)
			(fill no)
			(layer "B.Fab")
		)
		(pad "1" smd circle
			(at 0 0 180)
			(size 0.6096 0.6096)
			(layers "B.Cu" "B.Mask" "B.Paste")
			(net "TP_USB_OCS_N2")
		)
	)
)
